# BASEBOARD_FAB2 (Tioga Pass) — schematic netlist excerpt (pin names and nets, part order shuffled) for the footprints in the layout excerpt that follows; sources: Cadence DE-HDL packaged netlist, KiCad conversion of Wiwynn_Tioga_Pass_MB.brd

C5D56  CAP_A  22.0UF 4V 20% X6S  pkg 0603V  page 217 : A = PVDDQ_ABC ; B = GND
R8B23  RES  1.00K 1% CHIP  pkg 0402  page 133 : A = P3V3_STBY ; B = FM_XRC_PRESENT_N

(kicad_pcb
	(version 20260206)
	(generator "pcbnew")
	(generator_version "10.0")
	(general
		(thickness 1.6)
		(legacy_teardrops no)
	)
	(paper "A4")
	(title_block
		(title "Wiwynn_Tioga_Pass_MB.brd")
		(comment 1 "Tioga Pass / footprints 4-5 of 4770")
	)
	(layers
		(0 "F.Cu" signal "TOP")
		(4 "In1.Cu" signal "L2GND")
		(6 "In2.Cu" signal "L3")
		(8 "In3.Cu" signal "L4GND")
		(10 "In4.Cu" signal "L5")
		(12 "In5.Cu" signal "L6GND")
		(14 "In6.Cu" signal "L7VCC")
		(16 "In7.Cu" signal "L8VCC")
		(18 "In8.Cu" signal "L9GND")
		(20 "In9.Cu" signal "L10")
		(22 "In10.Cu" signal "L11GND")
		(24 "In11.Cu" signal "L12")
		(26 "In12.Cu" signal "L13GND")
		(2 "B.Cu" signal "BOTTOM")
		(9 "F.Adhes" user "F.Adhesive")
		(11 "B.Adhes" user "B.Adhesive")
		(13 "F.Paste" user "Package Geometry/Pastemask Top")
		(15 "B.Paste" user "Package Geometry/Pastemask Bottom")
		(5 "F.SilkS" user "Ref Des/Silkscreen Top")
		(7 "B.SilkS" user "Ref Des/Silkscreen Bottom")
		(1 "F.Mask" user "Board Geometry/Soldermask Top")
		(3 "B.Mask" user "Board Geometry/Soldermask Bottom")
		(17 "Dwgs.User" user "User.Drawings")
		(19 "Cmts.User" user "User.Comments")
		(21 "Eco1.User" user "User.Eco1")
		(23 "Eco2.User" user "User.Eco2")
		(25 "Edge.Cuts" user "Board Geometry/Outline")
		(27 "Margin" user)
		(31 "F.CrtYd" user "Package Geometry/Place Bound Top")
		(29 "B.CrtYd" user "Package Geometry/Place Bound Bottom")
		(35 "F.Fab" user "Ref Des/Assembly Top")
		(33 "B.Fab" user "Ref Des/Assembly Bottom")
	)
	(footprint ""
		(layer "F.Cu")
		(at 265.901424 -68.412614 180)
		(property "Reference" "C5D56"
			(at 0 0 180)
			(layer "F.SilkS")
			(hide yes)
			(effects
				(font
					(size 1.27 1.27)
				)
			)
		)
		(property "Value" ""
			(at 0 0 180)
			(layer "F.Fab")
			(effects
				(font
					(size 1.27 1.27)
				)
			)
		)
		(duplicate_pad_numbers_are_jumpers no)
		(fp_poly
			(pts
				(xy -0.4953 -0.2032) (xy 0.4953 -0.2032) (xy 0.4953 1.6002) (xy -0.4953 1.6002)
			)
			(stroke
				(width 0)
				(type default)
			)
			(fill no)
			(layer "F.CrtYd")
		)
		(fp_line
			(start 0.4953 1.6002)
			(end -0.4953 1.6002)
			(stroke
				(width 0.1)
				(type default)
			)
			(layer "F.Fab")
		)
		(fp_line
			(start 0.4953 -0.2032)
			(end 0.4953 1.6002)
			(stroke
				(width 0.1)
				(type default)
			)
			(layer "F.Fab")
		)
		(fp_line
			(start -0.4953 1.6002)
			(end -0.4953 -0.2032)
			(stroke
				(width 0.1)
				(type default)
			)
			(layer "F.Fab")
		)
		(fp_line
			(start -0.4953 -0.2032)
			(end 0.4953 -0.2032)
			(stroke
				(width 0.1)
				(type default)
			)
			(layer "F.Fab")
		)
		(pad "1" smd rect
			(at 0 0 180)
			(size 0.762 0.889)
			(layers "F.Cu" "F.Mask" "F.Paste")
			(net "PVDDQ_ABC")
		)
		(pad "2" smd rect
			(at 0 1.397 180)
			(size 0.762 0.889)
			(layers "F.Cu" "F.Mask" "F.Paste")
			(net "GND")
		)
		(zone
			(layer "F.Cu")
			(hatch none 0.5)
			(connect_pads
				(clearance 0)
			)
			(min_thickness 0.25)
			(keepout
				(tracks not_allowed)
				(vias allowed)
				(pads allowed)
				(copperpour not_allowed)
				(footprints allowed)
			)
			(placement
				(enabled no)
				(sheetname "")
			)
			(fill
				(thermal_gap 0.5)
				(thermal_bridge_width 0.5)
				(island_removal_mode 0)
			)
			(polygon
				(pts
					(xy 266.282424 -68.857114) (xy 265.520424 -68.857114) (xy 265.520424 -69.365114) (xy 266.282424 -69.365114)
				)
			)
		)
	)
	(footprint ""
		(layer "F.Cu")
		(at 408.728926 -115.521486 -90)
		(property "Reference" "R8B23"
			(at 0 0 270)
			(layer "F.SilkS")
			(hide yes)
			(effects
				(font
					(size 1.27 1.27)
				)
			)
		)
		(property "Value" ""
			(at 0 0 270)
			(layer "F.Fab")
			(effects
				(font
					(size 1.27 1.27)
				)
			)
		)
		(duplicate_pad_numbers_are_jumpers no)
		(fp_poly
			(pts
				(xy -0.2794 -0.1016) (xy 0.2794 -0.1016) (xy 0.2794 0.9906) (xy -0.2794 0.9906)
			)
			(stroke
				(width 0)
				(type default)
			)
			(fill no)
			(layer "F.CrtYd")
		)
		(fp_line
			(start -0.2794 0.9906)
			(end 0.2794 0.9906)
			(stroke
				(width 0.1)
				(type default)
			)
			(layer "F.Fab")
		)
		(fp_line
			(start 0.2794 0.9906)
			(end 0.2794 -0.1016)
			(stroke
				(width 0.1)
				(type default)
			)
			(layer "F.Fab")
		)
		(fp_line
			(start -0.2794 -0.1016)
			(end -0.2794 0.9906)
			(stroke
				(width 0.1)
				(type default)
			)
			(layer "F.Fab")
		)
		(fp_line
			(start 0.2794 -0.1016)
			(end -0.2794 -0.1016)
			(stroke
				(width 0.1)
				(type default)
			)
			(layer "F.Fab")
		)
		(pad "1" smd rect
			(at 0 0 270)
			(size 0.508 0.508)
			(layers "F.Cu" "F.Mask" "F.Paste")
			(net "P3V3_STBY")
		)
		(pad "2" smd rect
			(at 0 0.889 270)
			(size 0.508 0.508)
			(layers "F.Cu" "F.Mask" "F.Paste")
			(net "FM_XRC_PRESENT_N")
		)
		(zone
			(layer "F.Cu")
			(hatch none 0.5)
			(connect_pads
				(clearance 0)
			)
			(min_thickness 0.25)
			(keepout
				(tracks not_allowed)
				(vias allowed)
				(pads allowed)
				(copperpour not_allowed)
				(footprints allowed)
			)
			(placement
				(enabled no)
				(sheetname "")
			)
			(fill
				(thermal_gap 0.5)
				(thermal_bridge_width 0.5)
				(island_removal_mode 0)
			)
			(polygon
				(pts
					(xy 408.093926 -115.775486) (xy 408.093926 -115.267486) (xy 408.474926 -115.267486) (xy 408.474926 -115.775486)
				)
			)
		)
		(zone
			(layer "F.Cu")
			(hatch none 0.5)
			(connect_pads
				(clearance 0)
			)
			(min_thickness 0.25)
			(keepout
				(tracks allowed)
				(vias not_allowed)
				(pads allowed)
				(copperpour not_allowed)
				(footprints allowed)
			)
			(placement
				(enabled no)
				(sheetname "")
			)
			(fill
				(thermal_gap 0.5)
				(thermal_bridge_width 0.5)
				(island_removal_mode 0)
			)
			(polygon
				(pts
					(xy 408.474926 -115.775486) (xy 408.474926 -115.267486) (xy 408.093926 -115.267486) (xy 408.093926 -115.775486)
				)
			)
		)
	)
)
